# BASEBOARD_FAB2 (Tioga Pass) — schematic netlist excerpt (pin names and nets, part order shuffled) for the footprints in the layout excerpt that follows; sources: Cadence DE-HDL packaged netlist, KiCad conversion of Wiwynn_Tioga_Pass_MB.brd

C1A16  CAP  10UF 16V 10% X7R  pkg 0805  page 197 : A = P12V_NVDIMM_KLM ; B = GND
R1A1  RES  120.0 1% CHIP  pkg 0603  page 228 : A = PVDDQ_KLM ; B = GND
C840  CAP  0.22UF 16V 10% X7R  pkg 0402  page 244 : A = P3E_CPU0_PE1_PCH_TXN<12> ; B = P3E_CPU0_PE1_PCH_CON_TXN<12>

(kicad_pcb
	(version 20260206)
	(generator "pcbnew")
	(generator_version "10.0")
	(general
		(thickness 1.6)
		(legacy_teardrops no)
	)
	(paper "A4")
	(title_block
		(title "Wiwynn_Tioga_Pass_MB.brd")
		(comment 1 "Tioga Pass / footprints 2103-2105 of 4770")
	)
	(layers
		(0 "F.Cu" signal "TOP")
		(4 "In1.Cu" signal "L2GND")
		(6 "In2.Cu" signal "L3")
		(8 "In3.Cu" signal "L4GND")
		(10 "In4.Cu" signal "L5")
		(12 "In5.Cu" signal "L6GND")
		(14 "In6.Cu" signal "L7VCC")
		(16 "In7.Cu" signal "L8VCC")
		(18 "In8.Cu" signal "L9GND")
		(20 "In9.Cu" signal "L10")
		(22 "In10.Cu" signal "L11GND")
		(24 "In11.Cu" signal "L12")
		(26 "In12.Cu" signal "L13GND")
		(2 "B.Cu" signal "BOTTOM")
		(9 "F.Adhes" user "F.Adhesive")
		(11 "B.Adhes" user "B.Adhesive")
		(13 "F.Paste" user "Package Geometry/Pastemask Top")
		(15 "B.Paste" user "Package Geometry/Pastemask Bottom")
		(5 "F.SilkS" user "Ref Des/Silkscreen Top")
		(7 "B.SilkS" user "Ref Des/Silkscreen Bottom")
		(1 "F.Mask" user "Board Geometry/Soldermask Top")
		(3 "B.Mask" user "Board Geometry/Soldermask Bottom")
		(17 "Dwgs.User" user "User.Drawings")
		(19 "Cmts.User" user "User.Comments")
		(21 "Eco1.User" user "User.Eco1")
		(23 "Eco2.User" user "User.Eco2")
		(25 "Edge.Cuts" user "Board Geometry/Outline")
		(27 "Margin" user)
		(31 "F.CrtYd" user "Package Geometry/Place Bound Top")
		(29 "B.CrtYd" user "Package Geometry/Place Bound Bottom")
		(35 "F.Fab" user "Ref Des/Assembly Top")
		(33 "B.Fab" user "Ref Des/Assembly Bottom")
	)
	(footprint ""
		(layer "F.Cu")
		(at 13.35278 -154.178 -90)
		(property "Reference" "R1A1"
			(at 0 0 270)
			(layer "F.SilkS")
			(hide yes)
			(effects
				(font
					(size 1.27 1.27)
				)
			)
		)
		(property "Value" ""
			(at 0 0 270)
			(layer "F.Fab")
			(effects
				(font
					(size 1.27 1.27)
				)
			)
		)
		(duplicate_pad_numbers_are_jumpers no)
		(fp_rect
			(start 0.4953 1.6002)
			(end -0.4953 -0.2032)
			(stroke
				(width 0)
				(type default)
			)
			(fill no)
			(layer "F.CrtYd")
		)
		(fp_line
			(start -0.4953 1.6002)
			(end -0.4953 -0.2032)
			(stroke
				(width 0.1)
				(type default)
			)
			(layer "F.Fab")
		)
		(fp_line
			(start 0.4953 1.6002)
			(end -0.4953 1.6002)
			(stroke
				(width 0.1)
				(type default)
			)
			(layer "F.Fab")
		)
		(fp_line
			(start -0.4953 -0.2032)
			(end 0.4953 -0.2032)
			(stroke
				(width 0.1)
				(type default)
			)
			(layer "F.Fab")
		)
		(fp_line
			(start 0.4953 -0.2032)
			(end 0.4953 1.6002)
			(stroke
				(width 0.1)
				(type default)
			)
			(layer "F.Fab")
		)
		(pad "1" smd rect
			(at 0 0 270)
			(size 0.762 0.889)
			(layers "F.Cu" "F.Mask" "F.Paste")
			(net "PVDDQ_KLM")
		)
		(pad "2" smd rect
			(at 0 1.397 270)
			(size 0.762 0.889)
			(layers "F.Cu" "F.Mask" "F.Paste")
			(net "GND")
		)
		(zone
			(layer "F.Cu")
			(hatch none 0.5)
			(connect_pads
				(clearance 0)
			)
			(min_thickness 0.25)
			(keepout
				(tracks allowed)
				(vias not_allowed)
				(pads allowed)
				(copperpour not_allowed)
				(footprints allowed)
			)
			(placement
				(enabled no)
				(sheetname "")
			)
			(fill
				(thermal_gap 0.5)
				(thermal_bridge_width 0.5)
				(island_removal_mode 0)
			)
			(polygon
				(pts
					(xy 12.40028 -153.797) (xy 12.90828 -153.797) (xy 12.90828 -154.559) (xy 12.40028 -154.559)
				)
			)
		)
		(zone
			(layer "F.Cu")
			(hatch none 0.5)
			(connect_pads
				(clearance 0)
			)
			(min_thickness 0.25)
			(keepout
				(tracks not_allowed)
				(vias allowed)
				(pads allowed)
				(copperpour not_allowed)
				(footprints allowed)
			)
			(placement
				(enabled no)
				(sheetname "")
			)
			(fill
				(thermal_gap 0.5)
				(thermal_bridge_width 0.5)
				(island_removal_mode 0)
			)
			(polygon
				(pts
					(xy 12.40028 -153.797) (xy 12.90828 -153.797) (xy 12.90828 -154.559) (xy 12.40028 -154.559)
				)
			)
		)
	)
	(footprint ""
		(layer "F.Cu")
		(at 28.380182 -140.1826 -90)
		(property "Reference" "C1A16"
			(at 0 0 270)
			(layer "F.SilkS")
			(hide yes)
			(effects
				(font
					(size 1.27 1.27)
				)
			)
		)
		(property "Value" ""
			(at 0 0 270)
			(layer "F.Fab")
			(effects
				(font
					(size 1.27 1.27)
				)
			)
		)
		(duplicate_pad_numbers_are_jumpers no)
		(fp_poly
			(pts
				(xy -0.7239 -0.2159) (xy 0.7239 -0.2159) (xy 0.7239 1.9939) (xy -0.7239 1.9939)
			)
			(stroke
				(width 0)
				(type default)
			)
			(fill no)
			(layer "F.CrtYd")
		)
		(fp_line
			(start -0.7239 1.9939)
			(end 0.7239 1.9939)
			(stroke
				(width 0.1)
				(type default)
			)
			(layer "F.Fab")
		)
		(fp_line
			(start 0.7239 1.9939)
			(end 0.7239 -0.2159)
			(stroke
				(width 0.1)
				(type default)
			)
			(layer "F.Fab")
		)
		(fp_line
			(start -0.7239 -0.2159)
			(end -0.7239 1.9939)
			(stroke
				(width 0.1)
				(type default)
			)
			(layer "F.Fab")
		)
		(fp_line
			(start 0.7239 -0.2159)
			(end -0.7239 -0.2159)
			(stroke
				(width 0.1)
				(type default)
			)
			(layer "F.Fab")
		)
		(pad "1" smd rect
			(at 0 0 270)
			(size 1.27 1.016)
			(layers "F.Cu" "F.Mask" "F.Paste")
			(net "P12V_NVDIMM_KLM")
		)
		(pad "2" smd rect
			(at 0 1.778 270)
			(size 1.27 1.016)
			(layers "F.Cu" "F.Mask" "F.Paste")
			(net "GND")
		)
		(zone
			(layer "F.Cu")
			(hatch none 0.5)
			(connect_pads
				(clearance 0)
			)
			(min_thickness 0.25)
			(keepout
				(tracks not_allowed)
				(vias allowed)
				(pads allowed)
				(copperpour not_allowed)
				(footprints allowed)
			)
			(placement
				(enabled no)
				(sheetname "")
			)
			(fill
				(thermal_gap 0.5)
				(thermal_bridge_width 0.5)
				(island_removal_mode 0)
			)
			(polygon
				(pts
					(xy 27.872182 -140.8176) (xy 27.872182 -139.5476) (xy 27.110182 -139.5476) (xy 27.110182 -140.8176)
				)
			)
		)
	)
	(footprint ""
		(layer "F.Cu")
		(at 321.16522 -120.53316 -90)
		(property "Reference" "C840"
			(at -0.8382 -0.67818 270)
			(unlocked yes)
			(layer "F.SilkS")
			(effects
				(font
					(size 0.4064 0.254)
					(thickness 0.1524)
				)
				(justify left)
			)
		)
		(property "Value" ""
			(at 0 0 270)
			(layer "F.Fab")
			(effects
				(font
					(size 1.27 1.27)
				)
			)
		)
		(duplicate_pad_numbers_are_jumpers no)
		(fp_poly
			(pts
				(xy 0.3048 -0.1016) (xy 0.3048 0.9906) (xy -0.3048 0.9906) (xy -0.3048 -0.1016)
			)
			(stroke
				(width 0)
				(type default)
			)
			(fill no)
			(layer "F.CrtYd")
		)
		(fp_line
			(start -0.3048 0.9906)
			(end 0.3048 0.9906)
			(stroke
				(width 0.1)
				(type default)
			)
			(layer "F.Fab")
		)
		(fp_line
			(start 0.3048 0.9906)
			(end 0.3048 -0.1016)
			(stroke
				(width 0.1)
				(type default)
			)
			(layer "F.Fab")
		)
		(fp_line
			(start -0.3048 -0.1016)
			(end -0.3048 0.9906)
			(stroke
				(width 0.1)
				(type default)
			)
			(layer "F.Fab")
		)
		(fp_line
			(start 0.3048 -0.1016)
			(end -0.3048 -0.1016)
			(stroke
				(width 0.1)
				(type default)
			)
			(layer "F.Fab")
		)
		(pad "1" smd rect
			(at 0 0 270)
			(size 0.508 0.508)
			(layers "F.Cu" "F.Mask" "F.Paste")
			(net "P3E_CPU0_PE1_PCH_TXN<12>")
		)
		(pad "2" smd rect
			(at 0 0.889 270)
			(size 0.508 0.508)
			(layers "F.Cu" "F.Mask" "F.Paste")
			(net "P3E_CPU0_PE1_PCH_CON_TXN<12>")
		)
		(zone
			(layer "F.Cu")
			(hatch none 0.5)
			(connect_pads
				(clearance 0)
			)
			(min_thickness 0.25)
			(keepout
				(tracks not_allowed)
				(vias allowed)
				(pads allowed)
				(copperpour not_allowed)
				(footprints allowed)
			)
			(placement
				(enabled no)
				(sheetname "")
			)
			(fill
				(thermal_gap 0.5)
				(thermal_bridge_width 0.5)
				(island_removal_mode 0)
			)
			(polygon
				(pts
					(xy 320.53022 -120.78716) (xy 320.53022 -120.27916) (xy 320.91122 -120.27916) (xy 320.91122 -120.78716)
				)
			)
		)
		(zone
			(layer "F.Cu")
			(hatch none 0.5)
			(connect_pads
				(clearance 0)
			)
			(min_thickness 0.25)
			(keepout
				(tracks allowed)
				(vias not_allowed)
				(pads allowed)
				(copperpour not_allowed)
				(footprints allowed)
			)
			(placement
				(enabled no)
				(sheetname "")
			)
			(fill
				(thermal_gap 0.5)
				(thermal_bridge_width 0.5)
				(island_removal_mode 0)
			)
			(polygon
				(pts
					(xy 320.91122 -120.78716) (xy 320.91122 -120.27916) (xy 320.53022 -120.27916) (xy 320.53022 -120.78716)
				)
			)
		)
	)
)
